(kicad_pcb
	(version 20260206)
	(generator "pcbnew")
	(generator_version "10.0")
	(general
		(thickness 1.6)
		(legacy_teardrops no)
	)
	(paper "A4")
	(title_block
		(title "04192023_DAF0TMB3IC0_F0TG_MB_C_brd_V02_OCP.brd")
		(comment 1 "Grand Teton / footprints 7930-7935 of 8354")
	)
	(layers
		(0 "F.Cu" signal "TOP")
		(4 "In1.Cu" signal "GND")
		(6 "In2.Cu" signal "IN1")
		(8 "In3.Cu" signal "GND1")
		(10 "In4.Cu" signal "IN2")
		(12 "In5.Cu" signal "GND2")
		(14 "In6.Cu" signal "IN3")
		(16 "In7.Cu" signal "GND3")
		(18 "In8.Cu" signal "VCC")
		(20 "In9.Cu" signal "VCC1")
		(22 "In10.Cu" signal "GND4")
		(24 "In11.Cu" signal "IN4")
		(26 "In12.Cu" signal "GND5")
		(28 "In13.Cu" signal "IN5")
		(30 "In14.Cu" signal "GND6")
		(32 "In15.Cu" signal "IN6")
		(34 "In16.Cu" signal "GND7")
		(2 "B.Cu" signal "BOTTOM")
		(9 "F.Adhes" user "F.Adhesive")
		(11 "B.Adhes" user "B.Adhesive")
		(13 "F.Paste" user "Package Geometry/Pastemask Top")
		(15 "B.Paste" user "Package Geometry/Pastemask Bottom")
		(5 "F.SilkS" user "Ref Des/Silkscreen Top")
		(7 "B.SilkS" user "Ref Des/Silkscreen Bottom")
		(1 "F.Mask" user "Board Geometry/Soldermask Top")
		(3 "B.Mask" user "Board Geometry/Soldermask Bottom")
		(17 "Dwgs.User" user "User.Drawings")
		(19 "Cmts.User" user "User.Comments")
		(21 "Eco1.User" user "User.Eco1")
		(23 "Eco2.User" user "User.Eco2")
		(25 "Edge.Cuts" user "Board Geometry/Outline")
		(27 "Margin" user)
		(31 "F.CrtYd" user "Package Geometry/Place Bound Top")
		(29 "B.CrtYd" user "Package Geometry/Place Bound Bottom")
		(35 "F.Fab" user "Ref Des/Assembly Top")
		(33 "B.Fab" user "Ref Des/Assembly Bottom")
	)
	(footprint ""
		(layer "B.Cu")
		(at 173.213776 -19.209258)
		(property "Reference" "R6028"
			(at 0 0 0)
			(layer "B.SilkS")
			(hide yes)
			(effects
				(font
					(size 1.27 1.27)
				)
				(justify mirror)
			)
		)
		(property "Value" ""
			(at 0 0 0)
			(layer "B.Fab")
			(effects
				(font
					(size 1.27 1.27)
				)
				(justify mirror)
			)
		)
		(duplicate_pad_numbers_are_jumpers no)
		(fp_line
			(start -0.7874 -0.4064)
			(end -0.7874 0.4064)
			(stroke
				(width 0.1524)
				(type default)
			)
			(layer "B.SilkS")
		)
		(fp_line
			(start -0.7874 0.4064)
			(end 0.7874 0.4064)
			(stroke
				(width 0.1524)
				(type default)
			)
			(layer "B.SilkS")
		)
		(fp_line
			(start 0.7874 -0.4064)
			(end -0.7874 -0.4064)
			(stroke
				(width 0.1524)
				(type default)
			)
			(layer "B.SilkS")
		)
		(fp_line
			(start 0.7874 0.4064)
			(end 0.7874 -0.4064)
			(stroke
				(width 0.1524)
				(type default)
			)
			(layer "B.SilkS")
		)
		(fp_line
			(start -0.67945 -0.3048)
			(end -0.67945 0.3048)
			(stroke
				(width 0.1)
				(type default)
			)
			(layer "B.Fab")
		)
		(fp_line
			(start -0.67945 0.3048)
			(end -0.120396 0.3048)
			(stroke
				(width 0.1)
				(type default)
			)
			(layer "B.Fab")
		)
		(fp_line
			(start -0.12065 -0.3048)
			(end -0.67945 -0.3048)
			(stroke
				(width 0.1)
				(type default)
			)
			(layer "B.Fab")
		)
		(fp_line
			(start -0.12065 -0.2794)
			(end -0.12065 -0.3048)
			(stroke
				(width 0.1)
				(type default)
			)
			(layer "B.Fab")
		)
		(fp_line
			(start -0.120396 0.2794)
			(end 0.12065 0.2794)
			(stroke
				(width 0.1)
				(type default)
			)
			(layer "B.Fab")
		)
		(fp_line
			(start -0.120396 0.3048)
			(end -0.120396 0.2794)
			(stroke
				(width 0.1)
				(type default)
			)
			(layer "B.Fab")
		)
		(fp_line
			(start 0.12065 -0.305054)
			(end 0.12065 -0.2794)
			(stroke
				(width 0.1)
				(type default)
			)
			(layer "B.Fab")
		)
		(fp_line
			(start 0.12065 -0.2794)
			(end -0.12065 -0.2794)
			(stroke
				(width 0.1)
				(type default)
			)
			(layer "B.Fab")
		)
		(fp_line
			(start 0.12065 0.2794)
			(end 0.12065 0.3048)
			(stroke
				(width 0.1)
				(type default)
			)
			(layer "B.Fab")
		)
		(fp_line
			(start 0.12065 0.3048)
			(end 0.67945 0.3048)
			(stroke
				(width 0.1)
				(type default)
			)
			(layer "B.Fab")
		)
		(fp_line
			(start 0.67945 -0.305054)
			(end 0.12065 -0.305054)
			(stroke
				(width 0.1)
				(type default)
			)
			(layer "B.Fab")
		)
		(fp_line
			(start 0.67945 0.3048)
			(end 0.67945 -0.305054)
			(stroke
				(width 0.1)
				(type default)
			)
			(layer "B.Fab")
		)
		(pad "1" smd circle
			(at 0.40005 0 180)
			(size 0 0)
			(layers "B.Cu" "B.Mask" "B.Paste")
			(net "FM_LPC_ESPI_SEL")
		)
		(pad "2" smd circle
			(at -0.40005 0 180)
			(size 0 0)
			(layers "B.Cu" "B.Mask" "B.Paste")
			(net "GND")
		)
	)
	(footprint ""
		(layer "B.Cu")
		(at 234.4801 -228.092 180)
		(property "Reference" "R150"
			(at 0 0 0)
			(layer "B.SilkS")
			(hide yes)
			(effects
				(font
					(size 1.27 1.27)
				)
				(justify mirror)
			)
		)
		(property "Value" ""
			(at 0 0 0)
			(layer "B.Fab")
			(effects
				(font
					(size 1.27 1.27)
				)
				(justify mirror)
			)
		)
		(duplicate_pad_numbers_are_jumpers no)
		(fp_line
			(start 0.7874 0.4064)
			(end 0.7874 -0.4064)
			(stroke
				(width 0.1524)
				(type default)
			)
			(layer "B.SilkS")
		)
		(fp_line
			(start 0.7874 -0.4064)
			(end -0.7874 -0.4064)
			(stroke
				(width 0.1524)
				(type default)
			)
			(layer "B.SilkS")
		)
		(fp_line
			(start -0.7874 0.4064)
			(end 0.7874 0.4064)
			(stroke
				(width 0.1524)
				(type default)
			)
			(layer "B.SilkS")
		)
		(fp_line
			(start -0.7874 -0.4064)
			(end -0.7874 0.4064)
			(stroke
				(width 0.1524)
				(type default)
			)
			(layer "B.SilkS")
		)
		(fp_line
			(start 0.67945 0.3048)
			(end 0.67945 -0.305054)
			(stroke
				(width 0.1)
				(type default)
			)
			(layer "B.Fab")
		)
		(fp_line
			(start 0.67945 -0.305054)
			(end 0.12065 -0.305054)
			(stroke
				(width 0.1)
				(type default)
			)
			(layer "B.Fab")
		)
		(fp_line
			(start 0.12065 0.3048)
			(end 0.67945 0.3048)
			(stroke
				(width 0.1)
				(type default)
			)
			(layer "B.Fab")
		)
		(fp_line
			(start 0.12065 0.2794)
			(end 0.12065 0.3048)
			(stroke
				(width 0.1)
				(type default)
			)
			(layer "B.Fab")
		)
		(fp_line
			(start 0.12065 -0.2794)
			(end -0.12065 -0.2794)
			(stroke
				(width 0.1)
				(type default)
			)
			(layer "B.Fab")
		)
		(fp_line
			(start 0.12065 -0.305054)
			(end 0.12065 -0.2794)
			(stroke
				(width 0.1)
				(type default)
			)
			(layer "B.Fab")
		)
		(fp_line
			(start -0.120396 0.3048)
			(end -0.120396 0.2794)
			(stroke
				(width 0.1)
				(type default)
			)
			(layer "B.Fab")
		)
		(fp_line
			(start -0.120396 0.2794)
			(end 0.12065 0.2794)
			(stroke
				(width 0.1)
				(type default)
			)
			(layer "B.Fab")
		)
		(fp_line
			(start -0.12065 -0.2794)
			(end -0.12065 -0.3048)
			(stroke
				(width 0.1)
				(type default)
			)
			(layer "B.Fab")
		)
		(fp_line
			(start -0.12065 -0.3048)
			(end -0.67945 -0.3048)
			(stroke
				(width 0.1)
				(type default)
			)
			(layer "B.Fab")
		)
		(fp_line
			(start -0.67945 0.3048)
			(end -0.120396 0.3048)
			(stroke
				(width 0.1)
				(type default)
			)
			(layer "B.Fab")
		)
		(fp_line
			(start -0.67945 -0.3048)
			(end -0.67945 0.3048)
			(stroke
				(width 0.1)
				(type default)
			)
			(layer "B.Fab")
		)
		(pad "1" smd rect
			(at 0.40005 0 180)
			(size 0.4572 0.508)
			(layers "B.Cu" "B.Mask" "B.Paste")
			(net "SMB_CPU0_CPU1_APML_SDA")
		)
		(pad "2" smd rect
			(at -0.40005 0 180)
			(size 0.4572 0.508)
			(layers "B.Cu" "B.Mask" "B.Paste")
			(net "SMB_CPU0_CPU1_APML_BUF1_SDA")
		)
	)
	(footprint ""
		(layer "B.Cu")
		(at 310.411876 -76.489814 -90)
		(property "Reference" "R3048"
			(at 0 0 90)
			(layer "B.SilkS")
			(hide yes)
			(effects
				(font
					(size 1.27 1.27)
				)
				(justify mirror)
			)
		)
		(property "Value" ""
			(at 0 0 90)
			(layer "B.Fab")
			(effects
				(font
					(size 1.27 1.27)
				)
				(justify mirror)
			)
		)
		(duplicate_pad_numbers_are_jumpers no)
		(fp_line
			(start -0.7874 0.4064)
			(end 0.7874 0.4064)
			(stroke
				(width 0.1524)
				(type default)
			)
			(layer "B.SilkS")
		)
		(fp_line
			(start 0.7874 0.4064)
			(end 0.7874 -0.4064)
			(stroke
				(width 0.1524)
				(type default)
			)
			(layer "B.SilkS")
		)
		(fp_line
			(start -0.7874 -0.4064)
			(end -0.7874 0.4064)
			(stroke
				(width 0.1524)
				(type default)
			)
			(layer "B.SilkS")
		)
		(fp_line
			(start 0.7874 -0.4064)
			(end -0.7874 -0.4064)
			(stroke
				(width 0.1524)
				(type default)
			)
			(layer "B.SilkS")
		)
		(fp_line
			(start -0.67945 0.3048)
			(end -0.120396 0.3048)
			(stroke
				(width 0.1)
				(type default)
			)
			(layer "B.Fab")
		)
		(fp_line
			(start -0.120396 0.3048)
			(end -0.120396 0.2794)
			(stroke
				(width 0.1)
				(type default)
			)
			(layer "B.Fab")
		)
		(fp_line
			(start 0.12065 0.3048)
			(end 0.67945 0.3048)
			(stroke
				(width 0.1)
				(type default)
			)
			(layer "B.Fab")
		)
		(fp_line
			(start 0.67945 0.3048)
			(end 0.67945 -0.305054)
			(stroke
				(width 0.1)
				(type default)
			)
			(layer "B.Fab")
		)
		(fp_line
			(start -0.120396 0.2794)
			(end 0.12065 0.2794)
			(stroke
				(width 0.1)
				(type default)
			)
			(layer "B.Fab")
		)
		(fp_line
			(start 0.12065 0.2794)
			(end 0.12065 0.3048)
			(stroke
				(width 0.1)
				(type default)
			)
			(layer "B.Fab")
		)
		(fp_line
			(start -0.12065 -0.2794)
			(end -0.12065 -0.3048)
			(stroke
				(width 0.1)
				(type default)
			)
			(layer "B.Fab")
		)
		(fp_line
			(start 0.12065 -0.2794)
			(end -0.12065 -0.2794)
			(stroke
				(width 0.1)
				(type default)
			)
			(layer "B.Fab")
		)
		(fp_line
			(start -0.67945 -0.3048)
			(end -0.67945 0.3048)
			(stroke
				(width 0.1)
				(type default)
			)
			(layer "B.Fab")
		)
		(fp_line
			(start -0.12065 -0.3048)
			(end -0.67945 -0.3048)
			(stroke
				(width 0.1)
				(type default)
			)
			(layer "B.Fab")
		)
		(fp_line
			(start 0.12065 -0.305054)
			(end 0.12065 -0.2794)
			(stroke
				(width 0.1)
				(type default)
			)
			(layer "B.Fab")
		)
		(fp_line
			(start 0.67945 -0.305054)
			(end 0.12065 -0.305054)
			(stroke
				(width 0.1)
				(type default)
			)
			(layer "B.Fab")
		)
		(pad "1" smd circle
			(at 0.40005 0 90)
			(size 0 0)
			(layers "B.Cu" "B.Mask" "B.Paste")
			(net "MB0_P12V_STBY_PWRGD")
		)
		(pad "2" smd circle
			(at -0.40005 0 90)
			(size 0 0)
			(layers "B.Cu" "B.Mask" "B.Paste")
			(net "PWRGD_PS_PWROK")
		)
	)
	(footprint ""
		(layer "B.Cu")
		(at 242.702842 -383.483358 180)
		(property "Reference" "PR2537"
			(at 0 0 0)
			(layer "B.SilkS")
			(hide yes)
			(effects
				(font
					(size 1.27 1.27)
				)
				(justify mirror)
			)
		)
		(property "Value" ""
			(at 0 0 0)
			(layer "B.Fab")
			(effects
				(font
					(size 1.27 1.27)
				)
				(justify mirror)
			)
		)
		(duplicate_pad_numbers_are_jumpers no)
		(fp_line
			(start 0.7874 0.4064)
			(end 0.7874 -0.4064)
			(stroke
				(width 0.1524)
				(type default)
			)
			(layer "B.SilkS")
		)
		(fp_line
			(start 0.7874 -0.4064)
			(end -0.7874 -0.4064)
			(stroke
				(width 0.1524)
				(type default)
			)
			(layer "B.SilkS")
		)
		(fp_line
			(start -0.7874 0.4064)
			(end 0.7874 0.4064)
			(stroke
				(width 0.1524)
				(type default)
			)
			(layer "B.SilkS")
		)
		(fp_line
			(start -0.7874 -0.4064)
			(end -0.7874 0.4064)
			(stroke
				(width 0.1524)
				(type default)
			)
			(layer "B.SilkS")
		)
		(fp_line
			(start 0.67945 0.3048)
			(end 0.67945 -0.305054)
			(stroke
				(width 0.1)
				(type default)
			)
			(layer "B.Fab")
		)
		(fp_line
			(start 0.67945 -0.305054)
			(end 0.12065 -0.305054)
			(stroke
				(width 0.1)
				(type default)
			)
			(layer "B.Fab")
		)
		(fp_line
			(start 0.12065 0.3048)
			(end 0.67945 0.3048)
			(stroke
				(width 0.1)
				(type default)
			)
			(layer "B.Fab")
		)
		(fp_line
			(start 0.12065 0.2794)
			(end 0.12065 0.3048)
			(stroke
				(width 0.1)
				(type default)
			)
			(layer "B.Fab")
		)
		(fp_line
			(start 0.12065 -0.2794)
			(end -0.12065 -0.2794)
			(stroke
				(width 0.1)
				(type default)
			)
			(layer "B.Fab")
		)
		(fp_line
			(start 0.12065 -0.305054)
			(end 0.12065 -0.2794)
			(stroke
				(width 0.1)
				(type default)
			)
			(layer "B.Fab")
		)
		(fp_line
			(start -0.120396 0.3048)
			(end -0.120396 0.2794)
			(stroke
				(width 0.1)
				(type default)
			)
			(layer "B.Fab")
		)
		(fp_line
			(start -0.120396 0.2794)
			(end 0.12065 0.2794)
			(stroke
				(width 0.1)
				(type default)
			)
			(layer "B.Fab")
		)
		(fp_line
			(start -0.12065 -0.2794)
			(end -0.12065 -0.3048)
			(stroke
				(width 0.1)
				(type default)
			)
			(layer "B.Fab")
		)
		(fp_line
			(start -0.12065 -0.3048)
			(end -0.67945 -0.3048)
			(stroke
				(width 0.1)
				(type default)
			)
			(layer "B.Fab")
		)
		(fp_line
			(start -0.67945 0.3048)
			(end -0.120396 0.3048)
			(stroke
				(width 0.1)
				(type default)
			)
			(layer "B.Fab")
		)
		(fp_line
			(start -0.67945 -0.3048)
			(end -0.67945 0.3048)
			(stroke
				(width 0.1)
				(type default)
			)
			(layer "B.Fab")
		)
		(pad "1" smd circle
			(at 0.40005 0)
			(size 0 0)
			(layers "B.Cu" "B.Mask" "B.Paste")
			(net "P12V_AUX")
		)
		(pad "2" smd circle
			(at -0.40005 0)
			(size 0 0)
			(layers "B.Cu" "B.Mask" "B.Paste")
			(net "P12V_HSC_GATE_RC")
		)
	)
	(footprint ""
		(layer "B.Cu")
		(at 43.265852 -384.28676 180)
		(property "Reference" "R723"
			(at 0 0 0)
			(layer "B.SilkS")
			(hide yes)
			(effects
				(font
					(size 1.27 1.27)
				)
				(justify mirror)
			)
		)
		(property "Value" ""
			(at 0 0 0)
			(layer "B.Fab")
			(effects
				(font
					(size 1.27 1.27)
				)
				(justify mirror)
			)
		)
		(duplicate_pad_numbers_are_jumpers no)
		(fp_line
			(start 0.32512 0.175006)
			(end 0.32512 -0.175006)
			(stroke
				(width 0.1)
				(type default)
			)
			(layer "B.Fab")
		)
		(fp_line
			(start 0.32512 -0.175006)
			(end -0.32512 -0.175006)
			(stroke
				(width 0.1)
				(type default)
			)
			(layer "B.Fab")
		)
		(fp_line
			(start -0.32512 0.175006)
			(end 0.32512 0.175006)
			(stroke
				(width 0.1)
				(type default)
			)
			(layer "B.Fab")
		)
		(fp_line
			(start -0.32512 -0.175006)
			(end -0.32512 0.175006)
			(stroke
				(width 0.1)
				(type default)
			)
			(layer "B.Fab")
		)
		(pad "1" smd rect
			(at 0.2667 0)
			(size 0.3048 0.381)
			(layers "B.Cu" "B.Mask" "B.Paste")
			(net "TEST1_RT_CPU1_P0")
		)
		(pad "2" smd rect
			(at -0.2667 0 180)
			(size 0.3048 0.381)
			(layers "B.Cu" "B.Mask" "B.Paste")
			(net "GND")
		)
	)
	(footprint ""
		(layer "B.Cu")
		(at 16.237712 -112.693958 180)
		(property "Reference" "C5236"
			(at 0 0 0)
			(layer "B.SilkS")
			(hide yes)
			(effects
				(font
					(size 1.27 1.27)
				)
				(justify mirror)
			)
		)
		(property "Value" ""
			(at 0 0 0)
			(layer "B.Fab")
			(effects
				(font
					(size 1.27 1.27)
				)
				(justify mirror)
			)
		)
		(duplicate_pad_numbers_are_jumpers no)
		(fp_line
			(start 0.7874 0.4064)
			(end 0.7874 -0.4064)
			(stroke
				(width 0.1524)
				(type default)
			)
			(layer "B.SilkS")
		)
		(fp_line
			(start 0.7874 -0.4064)
			(end -0.7874 -0.4064)
			(stroke
				(width 0.1524)
				(type default)
			)
			(layer "B.SilkS")
		)
		(fp_line
			(start -0.7874 0.4064)
			(end 0.7874 0.4064)
			(stroke
				(width 0.1524)
				(type default)
			)
			(layer "B.SilkS")
		)
		(fp_line
			(start -0.7874 -0.4064)
			(end -0.7874 0.4064)
			(stroke
				(width 0.1524)
				(type default)
			)
			(layer "B.SilkS")
		)
		(fp_line
			(start 0.67945 0.3048)
			(end 0.67945 -0.305054)
			(stroke
				(width 0.1)
				(type default)
			)
			(layer "B.Fab")
		)
		(fp_line
			(start 0.67945 -0.305054)
			(end 0.12065 -0.305054)
			(stroke
				(width 0.1)
				(type default)
			)
			(layer "B.Fab")
		)
		(fp_line
			(start 0.12065 0.3048)
			(end 0.67945 0.3048)
			(stroke
				(width 0.1)
				(type default)
			)
			(layer "B.Fab")
		)
		(fp_line
			(start 0.12065 0.2794)
			(end 0.12065 0.3048)
			(stroke
				(width 0.1)
				(type default)
			)
			(layer "B.Fab")
		)
		(fp_line
			(start 0.12065 -0.2794)
			(end -0.12065 -0.2794)
			(stroke
				(width 0.1)
				(type default)
			)
			(layer "B.Fab")
		)
		(fp_line
			(start 0.12065 -0.305054)
			(end 0.12065 -0.2794)
			(stroke
				(width 0.1)
				(type default)
			)
			(layer "B.Fab")
		)
		(fp_line
			(start -0.120396 0.3048)
			(end -0.120396 0.2794)
			(stroke
				(width 0.1)
				(type default)
			)
			(layer "B.Fab")
		)
		(fp_line
			(start -0.120396 0.2794)
			(end 0.12065 0.2794)
			(stroke
				(width 0.1)
				(type default)
			)
			(layer "B.Fab")
		)
		(fp_line
			(start -0.12065 -0.2794)
			(end -0.12065 -0.3048)
			(stroke
				(width 0.1)
				(type default)
			)
			(layer "B.Fab")
		)
		(fp_line
			(start -0.12065 -0.3048)
			(end -0.67945 -0.3048)
			(stroke
				(width 0.1)
				(type default)
			)
			(layer "B.Fab")
		)
		(fp_line
			(start -0.67945 0.3048)
			(end -0.120396 0.3048)
			(stroke
				(width 0.1)
				(type default)
			)
			(layer "B.Fab")
		)
		(fp_line
			(start -0.67945 -0.3048)
			(end -0.67945 0.3048)
			(stroke
				(width 0.1)
				(type default)
			)
			(layer "B.Fab")
		)
		(pad "1" smd circle
			(at 0.40005 0)
			(size 0 0)
			(layers "B.Cu" "B.Mask" "B.Paste")
			(net "PD_U5201_VREG")
		)
		(pad "2" smd circle
			(at -0.40005 0)
			(size 0 0)
			(layers "B.Cu" "B.Mask" "B.Paste")
			(net "GND")
		)
	)
)
